(kicad_pcb
	(version 20260206)
	(generator "pcbnew")
	(generator_version "10.0")
	(general
		(thickness 1.6)
		(legacy_teardrops no)
	)
	(paper "A4")
	(title_block
		(title "04192023_DAF0TMB3IC0_F0TG_MB_C_brd_V02_OCP.brd")
		(comment 1 "Grand Teton / footprints 2272-2278 of 8354")
	)
	(layers
		(0 "F.Cu" signal "TOP")
		(4 "In1.Cu" signal "GND")
		(6 "In2.Cu" signal "IN1")
		(8 "In3.Cu" signal "GND1")
		(10 "In4.Cu" signal "IN2")
		(12 "In5.Cu" signal "GND2")
		(14 "In6.Cu" signal "IN3")
		(16 "In7.Cu" signal "GND3")
		(18 "In8.Cu" signal "VCC")
		(20 "In9.Cu" signal "VCC1")
		(22 "In10.Cu" signal "GND4")
		(24 "In11.Cu" signal "IN4")
		(26 "In12.Cu" signal "GND5")
		(28 "In13.Cu" signal "IN5")
		(30 "In14.Cu" signal "GND6")
		(32 "In15.Cu" signal "IN6")
		(34 "In16.Cu" signal "GND7")
		(2 "B.Cu" signal "BOTTOM")
		(9 "F.Adhes" user "F.Adhesive")
		(11 "B.Adhes" user "B.Adhesive")
		(13 "F.Paste" user "Package Geometry/Pastemask Top")
		(15 "B.Paste" user "Package Geometry/Pastemask Bottom")
		(5 "F.SilkS" user "Ref Des/Silkscreen Top")
		(7 "B.SilkS" user "Ref Des/Silkscreen Bottom")
		(1 "F.Mask" user "Board Geometry/Soldermask Top")
		(3 "B.Mask" user "Board Geometry/Soldermask Bottom")
		(17 "Dwgs.User" user "User.Drawings")
		(19 "Cmts.User" user "User.Comments")
		(21 "Eco1.User" user "User.Eco1")
		(23 "Eco2.User" user "User.Eco2")
		(25 "Edge.Cuts" user "Board Geometry/Outline")
		(27 "Margin" user)
		(31 "F.CrtYd" user "Package Geometry/Place Bound Top")
		(29 "B.CrtYd" user "Package Geometry/Place Bound Bottom")
		(35 "F.Fab" user "Ref Des/Assembly Top")
		(33 "B.Fab" user "Ref Des/Assembly Bottom")
	)
	(footprint ""
		(layer "F.Cu")
		(at 271.080484 -113.156746)
		(property "Reference" "R3732"
			(at 0 0 0)
			(layer "F.SilkS")
			(hide yes)
			(effects
				(font
					(size 1.27 1.27)
				)
			)
		)
		(property "Value" ""
			(at 0 0 0)
			(layer "F.Fab")
			(effects
				(font
					(size 1.27 1.27)
				)
			)
		)
		(duplicate_pad_numbers_are_jumpers no)
		(fp_line
			(start -0.7874 -0.4064)
			(end 0.7874 -0.4064)
			(stroke
				(width 0.1524)
				(type default)
			)
			(layer "F.SilkS")
		)
		(fp_line
			(start -0.7874 0.4064)
			(end -0.7874 -0.4064)
			(stroke
				(width 0.1524)
				(type default)
			)
			(layer "F.SilkS")
		)
		(fp_line
			(start 0.7874 -0.4064)
			(end 0.7874 0.4064)
			(stroke
				(width 0.1524)
				(type default)
			)
			(layer "F.SilkS")
		)
		(fp_line
			(start 0.7874 0.4064)
			(end -0.7874 0.4064)
			(stroke
				(width 0.1524)
				(type default)
			)
			(layer "F.SilkS")
		)
		(fp_line
			(start -0.67945 -0.305054)
			(end -0.12065 -0.305054)
			(stroke
				(width 0.1)
				(type default)
			)
			(layer "F.Fab")
		)
		(fp_line
			(start -0.67945 0.3048)
			(end -0.67945 -0.305054)
			(stroke
				(width 0.1)
				(type default)
			)
			(layer "F.Fab")
		)
		(fp_line
			(start -0.12065 -0.305054)
			(end -0.12065 -0.2794)
			(stroke
				(width 0.1)
				(type default)
			)
			(layer "F.Fab")
		)
		(fp_line
			(start -0.12065 -0.2794)
			(end 0.12065 -0.2794)
			(stroke
				(width 0.1)
				(type default)
			)
			(layer "F.Fab")
		)
		(fp_line
			(start -0.12065 0.2794)
			(end -0.12065 0.3048)
			(stroke
				(width 0.1)
				(type default)
			)
			(layer "F.Fab")
		)
		(fp_line
			(start -0.12065 0.3048)
			(end -0.67945 0.3048)
			(stroke
				(width 0.1)
				(type default)
			)
			(layer "F.Fab")
		)
		(fp_line
			(start 0.120396 0.2794)
			(end -0.12065 0.2794)
			(stroke
				(width 0.1)
				(type default)
			)
			(layer "F.Fab")
		)
		(fp_line
			(start 0.120396 0.3048)
			(end 0.120396 0.2794)
			(stroke
				(width 0.1)
				(type default)
			)
			(layer "F.Fab")
		)
		(fp_line
			(start 0.12065 -0.3048)
			(end 0.67945 -0.3048)
			(stroke
				(width 0.1)
				(type default)
			)
			(layer "F.Fab")
		)
		(fp_line
			(start 0.12065 -0.2794)
			(end 0.12065 -0.3048)
			(stroke
				(width 0.1)
				(type default)
			)
			(layer "F.Fab")
		)
		(fp_line
			(start 0.67945 -0.3048)
			(end 0.67945 0.3048)
			(stroke
				(width 0.1)
				(type default)
			)
			(layer "F.Fab")
		)
		(fp_line
			(start 0.67945 0.3048)
			(end 0.120396 0.3048)
			(stroke
				(width 0.1)
				(type default)
			)
			(layer "F.Fab")
		)
		(pad "1" smd circle
			(at -0.40005 0)
			(size 0 0)
			(layers "F.Cu" "F.Mask" "F.Paste")
			(net "P3V3_AUX")
		)
		(pad "2" smd circle
			(at 0.40005 0)
			(size 0 0)
			(layers "F.Cu" "F.Mask" "F.Paste")
			(net "SMB_LM75_3_3V3AUX_SDA")
		)
	)
	(footprint ""
		(layer "F.Cu")
		(at 322.837048 -40.144954 180)
		(property "Reference" "R3688"
			(at 0 0 180)
			(layer "F.SilkS")
			(hide yes)
			(effects
				(font
					(size 1.27 1.27)
				)
			)
		)
		(property "Value" ""
			(at 0 0 180)
			(layer "F.Fab")
			(effects
				(font
					(size 1.27 1.27)
				)
			)
		)
		(duplicate_pad_numbers_are_jumpers no)
		(fp_line
			(start 0.7874 0.4064)
			(end -0.7874 0.4064)
			(stroke
				(width 0.1524)
				(type default)
			)
			(layer "F.SilkS")
		)
		(fp_line
			(start 0.7874 -0.4064)
			(end 0.7874 0.4064)
			(stroke
				(width 0.1524)
				(type default)
			)
			(layer "F.SilkS")
		)
		(fp_line
			(start -0.7874 0.4064)
			(end -0.7874 -0.4064)
			(stroke
				(width 0.1524)
				(type default)
			)
			(layer "F.SilkS")
		)
		(fp_line
			(start -0.7874 -0.4064)
			(end 0.7874 -0.4064)
			(stroke
				(width 0.1524)
				(type default)
			)
			(layer "F.SilkS")
		)
		(fp_line
			(start 0.67945 0.3048)
			(end 0.120396 0.3048)
			(stroke
				(width 0.1)
				(type default)
			)
			(layer "F.Fab")
		)
		(fp_line
			(start 0.67945 -0.3048)
			(end 0.67945 0.3048)
			(stroke
				(width 0.1)
				(type default)
			)
			(layer "F.Fab")
		)
		(fp_line
			(start 0.12065 -0.2794)
			(end 0.12065 -0.3048)
			(stroke
				(width 0.1)
				(type default)
			)
			(layer "F.Fab")
		)
		(fp_line
			(start 0.12065 -0.3048)
			(end 0.67945 -0.3048)
			(stroke
				(width 0.1)
				(type default)
			)
			(layer "F.Fab")
		)
		(fp_line
			(start 0.120396 0.3048)
			(end 0.120396 0.2794)
			(stroke
				(width 0.1)
				(type default)
			)
			(layer "F.Fab")
		)
		(fp_line
			(start 0.120396 0.2794)
			(end -0.12065 0.2794)
			(stroke
				(width 0.1)
				(type default)
			)
			(layer "F.Fab")
		)
		(fp_line
			(start -0.12065 0.3048)
			(end -0.67945 0.3048)
			(stroke
				(width 0.1)
				(type default)
			)
			(layer "F.Fab")
		)
		(fp_line
			(start -0.12065 0.2794)
			(end -0.12065 0.3048)
			(stroke
				(width 0.1)
				(type default)
			)
			(layer "F.Fab")
		)
		(fp_line
			(start -0.12065 -0.2794)
			(end 0.12065 -0.2794)
			(stroke
				(width 0.1)
				(type default)
			)
			(layer "F.Fab")
		)
		(fp_line
			(start -0.12065 -0.305054)
			(end -0.12065 -0.2794)
			(stroke
				(width 0.1)
				(type default)
			)
			(layer "F.Fab")
		)
		(fp_line
			(start -0.67945 0.3048)
			(end -0.67945 -0.305054)
			(stroke
				(width 0.1)
				(type default)
			)
			(layer "F.Fab")
		)
		(fp_line
			(start -0.67945 -0.305054)
			(end -0.12065 -0.305054)
			(stroke
				(width 0.1)
				(type default)
			)
			(layer "F.Fab")
		)
		(pad "1" smd rect
			(at -0.40005 0)
			(size 0.4572 0.508)
			(layers "F.Cu" "F.Mask" "F.Paste")
			(net "P1V581_PDB_ADC")
		)
		(pad "2" smd rect
			(at 0.40005 0)
			(size 0.4572 0.508)
			(layers "F.Cu" "F.Mask" "F.Paste")
			(net "P3V3_PDB_AUX_ADC_TIC")
		)
	)
	(footprint ""
		(layer "F.Cu")
		(at 355.616002 -256.012188 90)
		(property "Reference" "C2562"
			(at 0 0 90)
			(layer "F.SilkS")
			(hide yes)
			(effects
				(font
					(size 1.27 1.27)
				)
			)
		)
		(property "Value" ""
			(at 0 0 90)
			(layer "F.Fab")
			(effects
				(font
					(size 1.27 1.27)
				)
			)
		)
		(duplicate_pad_numbers_are_jumpers no)
		(fp_line
			(start 0.7874 -0.4064)
			(end 0.7874 0.4064)
			(stroke
				(width 0.1524)
				(type default)
			)
			(layer "F.SilkS")
		)
		(fp_line
			(start -0.7874 -0.4064)
			(end 0.7874 -0.4064)
			(stroke
				(width 0.1524)
				(type default)
			)
			(layer "F.SilkS")
		)
		(fp_line
			(start 0.7874 0.4064)
			(end -0.7874 0.4064)
			(stroke
				(width 0.1524)
				(type default)
			)
			(layer "F.SilkS")
		)
		(fp_line
			(start -0.7874 0.4064)
			(end -0.7874 -0.4064)
			(stroke
				(width 0.1524)
				(type default)
			)
			(layer "F.SilkS")
		)
		(fp_line
			(start -0.12065 -0.305054)
			(end -0.12065 -0.2794)
			(stroke
				(width 0.1)
				(type default)
			)
			(layer "F.Fab")
		)
		(fp_line
			(start -0.67945 -0.305054)
			(end -0.12065 -0.305054)
			(stroke
				(width 0.1)
				(type default)
			)
			(layer "F.Fab")
		)
		(fp_line
			(start 0.67945 -0.3048)
			(end 0.67945 0.3048)
			(stroke
				(width 0.1)
				(type default)
			)
			(layer "F.Fab")
		)
		(fp_line
			(start 0.12065 -0.3048)
			(end 0.67945 -0.3048)
			(stroke
				(width 0.1)
				(type default)
			)
			(layer "F.Fab")
		)
		(fp_line
			(start 0.12065 -0.2794)
			(end 0.12065 -0.3048)
			(stroke
				(width 0.1)
				(type default)
			)
			(layer "F.Fab")
		)
		(fp_line
			(start -0.12065 -0.2794)
			(end 0.12065 -0.2794)
			(stroke
				(width 0.1)
				(type default)
			)
			(layer "F.Fab")
		)
		(fp_line
			(start 0.120396 0.2794)
			(end -0.12065 0.2794)
			(stroke
				(width 0.1)
				(type default)
			)
			(layer "F.Fab")
		)
		(fp_line
			(start -0.12065 0.2794)
			(end -0.12065 0.3048)
			(stroke
				(width 0.1)
				(type default)
			)
			(layer "F.Fab")
		)
		(fp_line
			(start 0.67945 0.3048)
			(end 0.120396 0.3048)
			(stroke
				(width 0.1)
				(type default)
			)
			(layer "F.Fab")
		)
		(fp_line
			(start 0.120396 0.3048)
			(end 0.120396 0.2794)
			(stroke
				(width 0.1)
				(type default)
			)
			(layer "F.Fab")
		)
		(fp_line
			(start -0.12065 0.3048)
			(end -0.67945 0.3048)
			(stroke
				(width 0.1)
				(type default)
			)
			(layer "F.Fab")
		)
		(fp_line
			(start -0.67945 0.3048)
			(end -0.67945 -0.305054)
			(stroke
				(width 0.1)
				(type default)
			)
			(layer "F.Fab")
		)
		(pad "1" smd circle
			(at -0.40005 0 90)
			(size 0 0)
			(layers "F.Cu" "F.Mask" "F.Paste")
			(net "PVDDCR_SOC_P0")
		)
		(pad "2" smd circle
			(at 0.40005 0 90)
			(size 0 0)
			(layers "F.Cu" "F.Mask" "F.Paste")
			(net "GND")
		)
	)
	(footprint ""
		(layer "F.Cu")
		(at 321.107308 -105.44175)
		(property "Reference" "R1317"
			(at 0 0 0)
			(layer "F.SilkS")
			(hide yes)
			(effects
				(font
					(size 1.27 1.27)
				)
			)
		)
		(property "Value" ""
			(at 0 0 0)
			(layer "F.Fab")
			(effects
				(font
					(size 1.27 1.27)
				)
			)
		)
		(duplicate_pad_numbers_are_jumpers no)
		(fp_line
			(start -0.7874 -0.4064)
			(end 0.7874 -0.4064)
			(stroke
				(width 0.1524)
				(type default)
			)
			(layer "F.SilkS")
		)
		(fp_line
			(start -0.7874 0.4064)
			(end -0.7874 -0.4064)
			(stroke
				(width 0.1524)
				(type default)
			)
			(layer "F.SilkS")
		)
		(fp_line
			(start 0.7874 -0.4064)
			(end 0.7874 0.4064)
			(stroke
				(width 0.1524)
				(type default)
			)
			(layer "F.SilkS")
		)
		(fp_line
			(start 0.7874 0.4064)
			(end -0.7874 0.4064)
			(stroke
				(width 0.1524)
				(type default)
			)
			(layer "F.SilkS")
		)
		(fp_line
			(start -0.67945 -0.305054)
			(end -0.12065 -0.305054)
			(stroke
				(width 0.1)
				(type default)
			)
			(layer "F.Fab")
		)
		(fp_line
			(start -0.67945 0.3048)
			(end -0.67945 -0.305054)
			(stroke
				(width 0.1)
				(type default)
			)
			(layer "F.Fab")
		)
		(fp_line
			(start -0.12065 -0.305054)
			(end -0.12065 -0.2794)
			(stroke
				(width 0.1)
				(type default)
			)
			(layer "F.Fab")
		)
		(fp_line
			(start -0.12065 -0.2794)
			(end 0.12065 -0.2794)
			(stroke
				(width 0.1)
				(type default)
			)
			(layer "F.Fab")
		)
		(fp_line
			(start -0.12065 0.2794)
			(end -0.12065 0.3048)
			(stroke
				(width 0.1)
				(type default)
			)
			(layer "F.Fab")
		)
		(fp_line
			(start -0.12065 0.3048)
			(end -0.67945 0.3048)
			(stroke
				(width 0.1)
				(type default)
			)
			(layer "F.Fab")
		)
		(fp_line
			(start 0.120396 0.2794)
			(end -0.12065 0.2794)
			(stroke
				(width 0.1)
				(type default)
			)
			(layer "F.Fab")
		)
		(fp_line
			(start 0.120396 0.3048)
			(end 0.120396 0.2794)
			(stroke
				(width 0.1)
				(type default)
			)
			(layer "F.Fab")
		)
		(fp_line
			(start 0.12065 -0.3048)
			(end 0.67945 -0.3048)
			(stroke
				(width 0.1)
				(type default)
			)
			(layer "F.Fab")
		)
		(fp_line
			(start 0.12065 -0.2794)
			(end 0.12065 -0.3048)
			(stroke
				(width 0.1)
				(type default)
			)
			(layer "F.Fab")
		)
		(fp_line
			(start 0.67945 -0.3048)
			(end 0.67945 0.3048)
			(stroke
				(width 0.1)
				(type default)
			)
			(layer "F.Fab")
		)
		(fp_line
			(start 0.67945 0.3048)
			(end 0.120396 0.3048)
			(stroke
				(width 0.1)
				(type default)
			)
			(layer "F.Fab")
		)
		(pad "1" smd circle
			(at -0.40005 0)
			(size 0 0)
			(layers "F.Cu" "F.Mask" "F.Paste")
			(net "P3V3_AUX")
		)
		(pad "2" smd circle
			(at 0.40005 0)
			(size 0 0)
			(layers "F.Cu" "F.Mask" "F.Paste")
			(net "INA230_8_A1")
		)
	)
	(footprint ""
		(layer "F.Cu")
		(at 234.952286 -257.70713 180)
		(property "Reference" ""
			(at 0 0 180)
			(layer "F.SilkS")
			(hide yes)
			(effects
				(font
					(size 1.27 1.27)
				)
			)
		)
		(property "Value" ""
			(at 0 0 180)
			(layer "F.Fab")
			(effects
				(font
					(size 1.27 1.27)
				)
			)
		)
		(duplicate_pad_numbers_are_jumpers no)
		(pad "1" smd circle
			(at 0 0 180)
			(size 0.9906 0.9906)
			(layers "F.Cu" "F.Mask" "F.Paste")
			(net "Net_49")
		)
		(zone
			(layer "F.Cu")
			(hatch none 0.5)
			(connect_pads
				(clearance 0)
			)
			(min_thickness 0.25)
			(keepout
				(tracks not_allowed)
				(vias allowed)
				(pads allowed)
				(copperpour not_allowed)
				(footprints allowed)
			)
			(placement
				(enabled no)
				(sheetname "")
			)
			(fill
				(thermal_gap 0.5)
				(thermal_bridge_width 0.5)
				(island_removal_mode 0)
			)
			(polygon
				(pts
					(arc
						(start 236.577886 -257.70713)
						(mid 233.326686 -257.70713)
						(end 236.577886 -257.70713)
					)
				)
			)
		)
	)
	(footprint ""
		(layer "F.Cu")
		(at 123.825 -321.655948 90)
		(property "Reference" "R4306"
			(at 0 0 90)
			(layer "F.SilkS")
			(hide yes)
			(effects
				(font
					(size 1.27 1.27)
				)
			)
		)
		(property "Value" ""
			(at 0 0 90)
			(layer "F.Fab")
			(effects
				(font
					(size 1.27 1.27)
				)
			)
		)
		(duplicate_pad_numbers_are_jumpers no)
		(fp_line
			(start -0.422148 -0.4064)
			(end 0.416052 -0.4064)
			(stroke
				(width 0.1524)
				(type default)
			)
			(layer "F.SilkS")
		)
		(fp_line
			(start 0.7874 0.0254)
			(end 0.7874 0.4064)
			(stroke
				(width 0.1524)
				(type default)
			)
			(layer "F.SilkS")
		)
		(fp_line
			(start 0.7874 0.4064)
			(end -0.7874 0.4064)
			(stroke
				(width 0.1524)
				(type default)
			)
			(layer "F.SilkS")
		)
		(fp_line
			(start -0.7874 0.4064)
			(end -0.7874 0.0254)
			(stroke
				(width 0.1524)
				(type default)
			)
			(layer "F.SilkS")
		)
		(fp_line
			(start -0.12065 -0.305054)
			(end -0.12065 -0.2794)
			(stroke
				(width 0.1)
				(type default)
			)
			(layer "F.Fab")
		)
		(fp_line
			(start -0.67945 -0.305054)
			(end -0.12065 -0.305054)
			(stroke
				(width 0.1)
				(type default)
			)
			(layer "F.Fab")
		)
		(fp_line
			(start 0.67945 -0.3048)
			(end 0.67945 0.3048)
			(stroke
				(width 0.1)
				(type default)
			)
			(layer "F.Fab")
		)
		(fp_line
			(start 0.12065 -0.3048)
			(end 0.67945 -0.3048)
			(stroke
				(width 0.1)
				(type default)
			)
			(layer "F.Fab")
		)
		(fp_line
			(start 0.12065 -0.2794)
			(end 0.12065 -0.3048)
			(stroke
				(width 0.1)
				(type default)
			)
			(layer "F.Fab")
		)
		(fp_line
			(start -0.12065 -0.2794)
			(end 0.12065 -0.2794)
			(stroke
				(width 0.1)
				(type default)
			)
			(layer "F.Fab")
		)
		(fp_line
			(start 0.120396 0.2794)
			(end -0.12065 0.2794)
			(stroke
				(width 0.1)
				(type default)
			)
			(layer "F.Fab")
		)
		(fp_line
			(start -0.12065 0.2794)
			(end -0.12065 0.3048)
			(stroke
				(width 0.1)
				(type default)
			)
			(layer "F.Fab")
		)
		(fp_line
			(start 0.67945 0.3048)
			(end 0.120396 0.3048)
			(stroke
				(width 0.1)
				(type default)
			)
			(layer "F.Fab")
		)
		(fp_line
			(start 0.120396 0.3048)
			(end 0.120396 0.2794)
			(stroke
				(width 0.1)
				(type default)
			)
			(layer "F.Fab")
		)
		(fp_line
			(start -0.12065 0.3048)
			(end -0.67945 0.3048)
			(stroke
				(width 0.1)
				(type default)
			)
			(layer "F.Fab")
		)
		(fp_line
			(start -0.67945 0.3048)
			(end -0.67945 -0.305054)
			(stroke
				(width 0.1)
				(type default)
			)
			(layer "F.Fab")
		)
		(pad "1" smd circle
			(at -0.40005 0 90)
			(size 0 0)
			(layers "F.Cu" "F.Mask" "F.Paste")
			(net "CLK_100M_CPU1_CLK12_R_DN")
		)
		(pad "2" smd circle
			(at 0.40005 0 90)
			(size 0 0)
			(layers "F.Cu" "F.Mask" "F.Paste")
			(net "CLK_100M_CPU1_CLK12_DN")
		)
	)
	(footprint ""
		(layer "F.Cu")
		(at 9.29513 -98.184208 -90)
		(property "Reference" "C2030"
			(at 0 0 270)
			(layer "F.SilkS")
			(hide yes)
			(effects
				(font
					(size 1.27 1.27)
				)
			)
		)
		(property "Value" ""
			(at 0 0 270)
			(layer "F.Fab")
			(effects
				(font
					(size 1.27 1.27)
				)
			)
		)
		(duplicate_pad_numbers_are_jumpers no)
		(fp_line
			(start -0.7874 0.4064)
			(end -0.7874 -0.4064)
			(stroke
				(width 0.1524)
				(type default)
			)
			(layer "F.SilkS")
		)
		(fp_line
			(start 0.7874 0.4064)
			(end -0.7874 0.4064)
			(stroke
				(width 0.1524)
				(type default)
			)
			(layer "F.SilkS")
		)
		(fp_line
			(start -0.7874 -0.4064)
			(end 0.7874 -0.4064)
			(stroke
				(width 0.1524)
				(type default)
			)
			(layer "F.SilkS")
		)
		(fp_line
			(start 0.7874 -0.4064)
			(end 0.7874 0.4064)
			(stroke
				(width 0.1524)
				(type default)
			)
			(layer "F.SilkS")
		)
		(fp_line
			(start -0.67945 0.3048)
			(end -0.67945 -0.305054)
			(stroke
				(width 0.1)
				(type default)
			)
			(layer "F.Fab")
		)
		(fp_line
			(start -0.12065 0.3048)
			(end -0.67945 0.3048)
			(stroke
				(width 0.1)
				(type default)
			)
			(layer "F.Fab")
		)
		(fp_line
			(start 0.120396 0.3048)
			(end 0.120396 0.2794)
			(stroke
				(width 0.1)
				(type default)
			)
			(layer "F.Fab")
		)
		(fp_line
			(start 0.67945 0.3048)
			(end 0.120396 0.3048)
			(stroke
				(width 0.1)
				(type default)
			)
			(layer "F.Fab")
		)
		(fp_line
			(start -0.12065 0.2794)
			(end -0.12065 0.3048)
			(stroke
				(width 0.1)
				(type default)
			)
			(layer "F.Fab")
		)
		(fp_line
			(start 0.120396 0.2794)
			(end -0.12065 0.2794)
			(stroke
				(width 0.1)
				(type default)
			)
			(layer "F.Fab")
		)
		(fp_line
			(start -0.12065 -0.2794)
			(end 0.12065 -0.2794)
			(stroke
				(width 0.1)
				(type default)
			)
			(layer "F.Fab")
		)
		(fp_line
			(start 0.12065 -0.2794)
			(end 0.12065 -0.3048)
			(stroke
				(width 0.1)
				(type default)
			)
			(layer "F.Fab")
		)
		(fp_line
			(start 0.12065 -0.3048)
			(end 0.67945 -0.3048)
			(stroke
				(width 0.1)
				(type default)
			)
			(layer "F.Fab")
		)
		(fp_line
			(start 0.67945 -0.3048)
			(end 0.67945 0.3048)
			(stroke
				(width 0.1)
				(type default)
			)
			(layer "F.Fab")
		)
		(fp_line
			(start -0.67945 -0.305054)
			(end -0.12065 -0.305054)
			(stroke
				(width 0.1)
				(type default)
			)
			(layer "F.Fab")
		)
		(fp_line
			(start -0.12065 -0.305054)
			(end -0.12065 -0.2794)
			(stroke
				(width 0.1)
				(type default)
			)
			(layer "F.Fab")
		)
		(pad "1" smd circle
			(at -0.40005 0 270)
			(size 0 0)
			(layers "F.Cu" "F.Mask" "F.Paste")
			(net "USB_HUB_XTAL_OUT")
		)
		(pad "2" smd circle
			(at 0.40005 0 270)
			(size 0 0)
			(layers "F.Cu" "F.Mask" "F.Paste")
			(net "GND")
		)
	)
)
